# T6G (Grand Teton) — schematic netlist excerpt (pin names and nets, part order shuffled) for the footprints in the layout excerpt that follows; sources: Cadence DE-HDL packaged netlist, KiCad conversion of 04192023_DAF0TMB3IC0_F0TG_MB_C_brd_V02_OCP.brd

J20  SCONN288_DDR506112002KQ  IO  pkg DDR288S_1-1VXC  page 96
  VIN_BULK0  = P12V_MEM_CPU0
  RFU0  = NC
  VIN_MGMT  = P3V3_AUX
  HSCL  = I3C_SPD_DDRK_CPU0_SCL
  HSDA  = I3C_SPD_DDRK_CPU0_SDA
  VSS0  = GND
  DQ0_A  = M_K_CPU0_SA_DQ<0>
  VSS1  = GND
  DQ1_A  = M_K_CPU0_SA_DQ<1>
  VSS2  = GND
  DQS0_A_T  = M_K_CPU0_SA_DQS_DP<0>
  DQS0_A_C  = M_K_CPU0_SA_DQS_DN<0>
  VSS3  = GND
  DQ4_A  = M_K_CPU0_SA_DQ<4>
  VSS4  = GND
  DQ5_A  = M_K_CPU0_SA_DQ<5>
  VSS5  = GND
  DQ8_A  = M_K_CPU0_SA_DQ<8>
  VSS6  = GND
  DQ9_A  = M_K_CPU0_SA_DQ<9>
  VSS7  = GND
  DQS1_A_T  = M_K_CPU0_SA_DQS_DP<1>
  DQS1_A_C  = M_K_CPU0_SA_DQS_DN<1>
  VSS8  = GND
  DQ12_A  = M_K_CPU0_SA_DQ<12>
  VSS9  = GND
  DQ13_A  = M_K_CPU0_SA_DQ<13>
  VSS10  = GND
  DQ16_A  = M_K_CPU0_SA_DQ<16>
  VSS11  = GND
  DQ17_A  = M_K_CPU0_SA_DQ<17>
  VSS12  = GND
  DQS2_A_T  = M_K_CPU0_SA_DQS_DP<2>
  DQS2_A_C  = M_K_CPU0_SA_DQS_DN<2>
  VSS13  = GND
  DQ20_A  = M_K_CPU0_SA_DQ<20>
  VSS14  = GND
  DQ21_A  = M_K_CPU0_SA_DQ<21>
  VSS15  = GND
  DQ24_A  = M_K_CPU0_SA_DQ<24>
  VSS16  = GND
  DQ25_A  = M_K_CPU0_SA_DQ<25>
  VSS17  = GND
  DQS3_A_T  = M_K_CPU0_SA_DQS_DP<3>
  DQS3_A_C  = M_K_CPU0_SA_DQS_DN<3>
  VSS18  = GND
  DQ28_A  = M_K_CPU0_SA_DQ<28>
  VSS19  = GND
  DQ29_A  = M_K_CPU0_SA_DQ<29>
  VSS20  = GND
  CB0_A  = M_K_CPU0_SA_CB<0>
  VSS21  = GND
  CB1_A  = M_K_CPU0_SA_CB<1>
  VSS22  = GND
  DQS4_A_T  = M_K_CPU0_SA_DQS_DP<4>
  DQS4_A_C  = M_K_CPU0_SA_DQS_DN<4>
  VSS23  = GND
  CB4_A  = M_K_CPU0_SA_CB<4>
  VSS24  = GND
  CB5_A  = M_K_CPU0_SA_CB<5>
  VSS25  = GND
  ALERT_N  = M_K_CPU0_ALERT_N
  VSS26  = GND
  CS0_A_N  = M_K_CPU0_SA_CS_N<0>
  VSS27  = GND
  CA0_A  = M_K_CPU0_SA_CA<0>
  VSS28  = GND
  CA2_A  = M_K_CPU0_SA_CA<2>
  VSS29  = GND
  CA4_A  = M_K_CPU0_SA_CA<4>
  VSS30  = GND
  CA6_A  = M_K_CPU0_SA_CA<6>
  VSS31  = GND
  PAR_A  = M_K_CPU0_SA_PAR
  VSS32  = GND
  CA0_B  = M_K_CPU0_SB_CA<0>
  VSS33  = GND
  CA2_B  = M_K_CPU0_SB_CA<2>
  VSS34  = GND
  CA4_B  = M_K_CPU0_SB_CA<4>
  VSS35  = GND
  CA6_B  = M_K_CPU0_SB_CA<6>
  VSS36  = GND
  CS0_B_N  = M_K_CPU0_SB_CS_N<0>
  VSS37  = GND
  \lbd||rsp_a_n\  = M_K_CPU0_SA_RSP<0>
  \lbs||rsp_b_n\  = M_K_CPU0_SB_RSP<0>
  VSS38  = GND
  CB4_B  = M_K_CPU0_SB_CB<4>
  VSS39  = GND
  CB5_B  = M_K_CPU0_SB_CB<5>
  VSS40  = GND
  \dqs9_b_t||tdqs9_b_t||dbi4_b_n\  = M_K_CPU0_SB_DQS_DP<9>
  \dqs9_b_c||tdqs9_b_c\  = M_K_CPU0_SB_DQS_DN<9>
  VSS41  = GND
  CB0_B  = M_K_CPU0_SB_CB<0>
  VSS42  = GND
  CB1_B  = M_K_CPU0_SB_CB<1>
  VSS43  = GND
  DQ0_B  = M_K_CPU0_SB_DQ<0>
  VSS44  = GND
  DQ1_B  = M_K_CPU0_SB_DQ<1>
  VSS45  = GND
  DQS0_B_T  = M_K_CPU0_SB_DQS_DP<0>
  DQS0_B_C  = M_K_CPU0_SB_DQS_DN<0>
  VSS46  = GND
  DQ4_B  = M_K_CPU0_SB_DQ<4>
  VSS47  = GND
  DQ5_B  = M_K_CPU0_SB_DQ<5>
  VSS48  = GND
  DQ8_B  = M_K_CPU0_SB_DQ<8>
  VSS49  = GND
  DQ9_B  = M_K_CPU0_SB_DQ<9>
  VSS50  = GND
  DQS1_B_T  = M_K_CPU0_SB_DQS_DP<1>
  DQS1_B_C  = M_K_CPU0_SB_DQS_DN<1>
  VSS51  = GND
  DQ12_B  = M_K_CPU0_SB_DQ<12>
  VSS52  = GND
  DQ13_B  = M_K_CPU0_SB_DQ<13>
  VSS53  = GND
  DQ16_B  = M_K_CPU0_SB_DQ<16>
  VSS54  = GND
  DQ17_B  = M_K_CPU0_SB_DQ<17>
  VSS55  = GND
  DQS2_B_T  = M_K_CPU0_SB_DQS_DP<2>
  DQS2_B_C  = M_K_CPU0_SB_DQS_DN<2>
  VSS56  = GND
  DQ20_B  = M_K_CPU0_SB_DQ<20>
  VSS57  = GND
  DQ21_B  = M_K_CPU0_SB_DQ<21>
  VSS58  = GND
  DQ24_B  = M_K_CPU0_SB_DQ<24>
  VSS59  = GND
  DQ25_B  = M_K_CPU0_SB_DQ<25>
  VSS60  = GND
  DQS3_B_T  = M_K_CPU0_SB_DQS_DP<3>
  DQS3_B_C  = M_K_CPU0_SB_DQS_DN<3>
  VSS61  = GND
  DQ28_B  = M_K_CPU0_SB_DQ<28>
  VSS62  = GND
  DQ29_B  = M_K_CPU0_SB_DQ<29>
  VSS63  = GND
  RFU1  = NC
  VIN_BULK1  = P12V_MEM_CPU0
  VIN_BULK2  = P12V_MEM_CPU0
  \pwr_good||fail_n\  = PWRGD_CHK_CPU0_DIMM
  HAS  = PD_CHK_CPU0_DIMM_SAA
  RFU2  = NC
  RFU3  = NC
  VSS64  = GND
  DQ2_A  = M_K_CPU0_SA_DQ<2>
  VSS65  = GND
  DQ3_A  = M_K_CPU0_SA_DQ<3>
  VSS66  = GND
  \dqs5_a_c||tdqs5_a_c||dqs5_a_t||tdqs5_a_t\  = M_K_CPU0_SA_DQS_DN<5>
  \dqs5_a_t||tdqs5_a_t\  = M_K_CPU0_SA_DQS_DP<5>
  VSS67  = GND
  DQ6_A  = M_K_CPU0_SA_DQ<6>
  VSS68  = GND
  DQ7_A  = M_K_CPU0_SA_DQ<7>
  VSS69  = GND
  DQ10_A  = M_K_CPU0_SA_DQ<10>
  VSS70  = GND
  DQ11_A  = M_K_CPU0_SA_DQ<11>
  VSS71  = GND
  \dqs6_a_c||tdqs6_a_c||dqs6_a_t||tdqs6_a_t\  = M_K_CPU0_SA_DQS_DN<6>
  \dqs6_a_t||tdqs6_a_t\  = M_K_CPU0_SA_DQS_DP<6>
  VSS72  = GND
  DQ14_A  = M_K_CPU0_SA_DQ<14>
  VSS73  = GND
  DQ15_A  = M_K_CPU0_SA_DQ<15>
  VSS74  = GND
  DQ18_A  = M_K_CPU0_SA_DQ<18>
  VSS75  = GND
  DQ19_A  = M_K_CPU0_SA_DQ<19>
  VSS76  = GND
  \dqs7_a_c||tdqs7_a_c\  = M_K_CPU0_SA_DQS_DN<7>
  \dqs7_a_t||tdqs7_a_t\  = M_K_CPU0_SA_DQS_DP<7>
  VSS77  = GND
  DQ22_A  = M_K_CPU0_SA_DQ<22>
  VSS78  = GND
  DQ23_A  = M_K_CPU0_SA_DQ<23>
  VSS79  = GND
  DQ26_A  = M_K_CPU0_SA_DQ<26>
  VSS80  = GND
  DQ27_A  = M_K_CPU0_SA_DQ<27>
  VSS81  = GND
  \dqs8_a_c||tdqs8_a_c\  = M_K_CPU0_SA_DQS_DN<8>
  \dqs8_a_t||tdqs8_a_t\  = M_K_CPU0_SA_DQS_DP<8>
  VSS82  = GND
  DQ30_A  = M_K_CPU0_SA_DQ<30>
  VSS83  = GND
  DQ31_A  = M_K_CPU0_SA_DQ<31>
  VSS84  = GND
  CB2_A  = M_K_CPU0_SA_CB<2>
  VSS85  = GND
  CB3_A  = M_K_CPU0_SA_CB<3>
  VSS86  = GND
  \dqs9_a_c||tdqs9_a_c\  = M_K_CPU0_SA_DQS_DN<9>
  \dqs9_a_t||tdqs9_a_t\  = M_K_CPU0_SA_DQS_DP<9>
  VSS87  = GND
  CB6_A  = M_K_CPU0_SA_CB<6>
  VSS88  = GND
  CB7_A  = M_K_CPU0_SA_CB<7>
  VSS89  = GND
  RESET_N  = M_K_CPU0_RESET_N
  VSS90  = GND
  CS1_A_N  = M_K_CPU0_SA_CS_N<1>
  VSS91  = GND
  CA1_A  = M_K_CPU0_SA_CA<1>
  VSS92  = GND
  CA3_A  = M_K_CPU0_SA_CA<3>
  VSS93  = GND
  CA5_A  = M_K_CPU0_SA_CA<5>
  VSS94  = GND
  CK_T  = M_K_CPU0_CLK_DP<0>
  CK_C  = M_K_CPU0_CLK_DN<0>
  VSS95  = GND
  RFU4  = NC
  CA1_B  = M_K_CPU0_SB_CA<1>
  VSS96  = GND
  CA3_B  = M_K_CPU0_SB_CA<3>
  VSS97  = GND
  CA5_B  = M_K_CPU0_SB_CA<5>
  VSS98  = GND
  PAR_B  = M_K_CPU0_SB_PAR
  VSS99  = GND
  CS1_B_N  = M_K_CPU0_SB_CS_N<1>
  VSS100  = GND
  RFU5  = NC
  RFU6  = NC
  VSS101  = GND
  CB6_B  = M_K_CPU0_SB_CB<6>
  VSS102  = GND
  CB7_B  = M_K_CPU0_SB_CB<7>
  VSS103  = GND
  DQS4_B_C  = M_K_CPU0_SB_DQS_DN<4>
  DQS4_B_T  = M_K_CPU0_SB_DQS_DP<4>
  VSS104  = GND
  CB2_B  = M_K_CPU0_SB_CB<2>
  VSS105  = GND
  CB3_B  = M_K_CPU0_SB_CB<3>
  VSS106  = GND
  DQ2_B  = M_K_CPU0_SB_DQ<2>
  VSS107  = GND
  DQ3_B  = M_K_CPU0_SB_DQ<3>
  VSS108  = GND
  \dqs5_b_c||tdqs5_b_c\  = M_K_CPU0_SB_DQS_DN<5>
  \dqs5_b_t||tdqs5_b_t\  = M_K_CPU0_SB_DQS_DP<5>
  VSS109  = GND
  DQ6_B  = M_K_CPU0_SB_DQ<6>
  VSS110  = GND
  DQ7_B  = M_K_CPU0_SB_DQ<7>
  VSS111  = GND
  DQ10_B  = M_K_CPU0_SB_DQ<10>
  VSS112  = GND
  DQ11_B  = M_K_CPU0_SB_DQ<11>
  VSS113  = GND
  \dqs6_b_c||tdqs6_b_c\  = M_K_CPU0_SB_DQS_DN<6>
  \dqs6_b_t||tdqs6_b_t\  = M_K_CPU0_SB_DQS_DP<6>
  VSS114  = GND
  DQ14_B  = M_K_CPU0_SB_DQ<14>
  VSS115  = GND
  DQ15_B  = M_K_CPU0_SB_DQ<15>
  VSS116  = GND
  DQ18_B  = M_K_CPU0_SB_DQ<18>
  VSS117  = GND
  DQ19_B  = M_K_CPU0_SB_DQ<19>
  VSS118  = GND
  \dqs7_b_c||tdqs7_b_c\  = M_K_CPU0_SB_DQS_DN<7>
  \dqs7_b_t||tdqs7_b_t\  = M_K_CPU0_SB_DQS_DP<7>
  VSS119  = GND
  DQ22_B  = M_K_CPU0_SB_DQ<22>
  VSS120  = GND
  DQ23_B  = M_K_CPU0_SB_DQ<23>
  VSS121  = GND
  DQ26_B  = M_K_CPU0_SB_DQ<26>
  VSS122  = GND
  DQ27_B  = M_K_CPU0_SB_DQ<27>
  VSS123  = GND
  \dqs8_b_c||tdqs8_b_c\  = M_K_CPU0_SB_DQS_DN<8>
  \dqs8_b_t||tdqs8_b_t\  = M_K_CPU0_SB_DQS_DP<8>
  VSS124  = GND
  DQ30_B  = M_K_CPU0_SB_DQ<30>
  VSS125  = GND
  DQ31_B  = M_K_CPU0_SB_DQ<31>
  VSS126  = GND
  G1  = GND
  G2  = GND
  G3  = GND

(kicad_pcb
	(version 20260206)
	(generator "pcbnew")
	(generator_version "10.0")
	(general
		(thickness 1.6)
		(legacy_teardrops no)
	)
	(paper "A4")
	(title_block
		(title "04192023_DAF0TMB3IC0_F0TG_MB_C_brd_V02_OCP.brd")
		(comment 1 "Grand Teton / footprint 2165 of 8354 (J20), pads 93-138 of 291")
	)
	(layers
		(0 "F.Cu" signal "TOP")
		(4 "In1.Cu" signal "GND")
		(6 "In2.Cu" signal "IN1")
		(8 "In3.Cu" signal "GND1")
		(10 "In4.Cu" signal "IN2")
		(12 "In5.Cu" signal "GND2")
		(14 "In6.Cu" signal "IN3")
		(16 "In7.Cu" signal "GND3")
		(18 "In8.Cu" signal "VCC")
		(20 "In9.Cu" signal "VCC1")
		(22 "In10.Cu" signal "GND4")
		(24 "In11.Cu" signal "IN4")
		(26 "In12.Cu" signal "GND5")
		(28 "In13.Cu" signal "IN5")
		(30 "In14.Cu" signal "GND6")
		(32 "In15.Cu" signal "IN6")
		(34 "In16.Cu" signal "GND7")
		(2 "B.Cu" signal "BOTTOM")
		(9 "F.Adhes" user "F.Adhesive")
		(11 "B.Adhes" user "B.Adhesive")
		(13 "F.Paste" user "Package Geometry/Pastemask Top")
		(15 "B.Paste" user "Package Geometry/Pastemask Bottom")
		(5 "F.SilkS" user "Ref Des/Silkscreen Top")
		(7 "B.SilkS" user "Ref Des/Silkscreen Bottom")
		(1 "F.Mask" user "Board Geometry/Soldermask Top")
		(3 "B.Mask" user "Board Geometry/Soldermask Bottom")
		(17 "Dwgs.User" user "User.Drawings")
		(19 "Cmts.User" user "User.Comments")
		(21 "Eco1.User" user "User.Eco1")
		(23 "Eco2.User" user "User.Eco2")
		(25 "Edge.Cuts" user "Board Geometry/Outline")
		(27 "Margin" user)
		(31 "F.CrtYd" user "Package Geometry/Place Bound Top")
		(29 "B.CrtYd" user "Package Geometry/Place Bound Bottom")
		(35 "F.Fab" user "Ref Des/Assembly Top")
		(33 "B.Fab" user "Ref Des/Assembly Bottom")
	)
	(footprint ""
		(layer "F.Cu")
		(at 444.594234 -255.560068 180)
		(property "Reference" "J20"
			(at 1.631188 -81.796128 0)
			(unlocked yes)
			(layer "F.SilkS")
			(effects
				(font
					(size 0.7874 0.5842)
					(thickness 0.1524)
				)
			)
		)
		(property "Value" ""
			(at 0 0 180)
			(layer "F.Fab")
			(effects
				(font
					(size 1.27 1.27)
				)
			)
		)
		(duplicate_pad_numbers_are_jumpers no)
		(pad "93" smd rect
			(at -2.050034 19.975068 90)
			(size 0.519938 1.4986)
			(layers "F.Cu" "F.Mask" "F.Paste")
			(net "M_K_CPU0_SB_DQS_DP<9>")
		)
		(pad "94" smd rect
			(at -2.050034 20.824952 90)
			(size 0.519938 1.4986)
			(layers "F.Cu" "F.Mask" "F.Paste")
			(net "M_K_CPU0_SB_DQS_DN<9>")
		)
		(pad "95" smd rect
			(at -2.050034 21.67509 90)
			(size 0.519938 1.4986)
			(layers "F.Cu" "F.Mask" "F.Paste")
			(net "GND")
		)
		(pad "96" smd rect
			(at -2.050034 22.524974 90)
			(size 0.519938 1.4986)
			(layers "F.Cu" "F.Mask" "F.Paste")
			(net "M_K_CPU0_SB_CB<0>")
		)
		(pad "97" smd rect
			(at -2.050034 23.375112 90)
			(size 0.519938 1.4986)
			(layers "F.Cu" "F.Mask" "F.Paste")
			(net "GND")
		)
		(pad "98" smd rect
			(at -2.050034 24.224996 90)
			(size 0.519938 1.4986)
			(layers "F.Cu" "F.Mask" "F.Paste")
			(net "M_K_CPU0_SB_CB<1>")
		)
		(pad "99" smd rect
			(at -2.050034 25.07488 90)
			(size 0.519938 1.4986)
			(layers "F.Cu" "F.Mask" "F.Paste")
			(net "GND")
		)
		(pad "100" smd rect
			(at -2.050034 25.925018 90)
			(size 0.519938 1.4986)
			(layers "F.Cu" "F.Mask" "F.Paste")
			(net "M_K_CPU0_SB_DQ<0>")
		)
		(pad "101" smd rect
			(at -2.050034 26.774902 90)
			(size 0.519938 1.4986)
			(layers "F.Cu" "F.Mask" "F.Paste")
			(net "GND")
		)
		(pad "102" smd rect
			(at -2.050034 27.62504 90)
			(size 0.519938 1.4986)
			(layers "F.Cu" "F.Mask" "F.Paste")
			(net "M_K_CPU0_SB_DQ<1>")
		)
		(pad "103" smd rect
			(at -2.050034 28.474924 90)
			(size 0.519938 1.4986)
			(layers "F.Cu" "F.Mask" "F.Paste")
			(net "GND")
		)
		(pad "104" smd rect
			(at -2.050034 29.325062 90)
			(size 0.519938 1.4986)
			(layers "F.Cu" "F.Mask" "F.Paste")
			(net "M_K_CPU0_SB_DQS_DP<0>")
		)
		(pad "105" smd rect
			(at -2.050034 30.174946 90)
			(size 0.519938 1.4986)
			(layers "F.Cu" "F.Mask" "F.Paste")
			(net "M_K_CPU0_SB_DQS_DN<0>")
		)
		(pad "106" smd rect
			(at -2.050034 31.025084 90)
			(size 0.519938 1.4986)
			(layers "F.Cu" "F.Mask" "F.Paste")
			(net "GND")
		)
		(pad "107" smd rect
			(at -2.050034 31.874968 90)
			(size 0.519938 1.4986)
			(layers "F.Cu" "F.Mask" "F.Paste")
			(net "M_K_CPU0_SB_DQ<4>")
		)
		(pad "108" smd rect
			(at -2.050034 32.725106 90)
			(size 0.519938 1.4986)
			(layers "F.Cu" "F.Mask" "F.Paste")
			(net "GND")
		)
		(pad "109" smd rect
			(at -2.050034 33.57499 90)
			(size 0.519938 1.4986)
			(layers "F.Cu" "F.Mask" "F.Paste")
			(net "M_K_CPU0_SB_DQ<5>")
		)
		(pad "110" smd rect
			(at -2.050034 34.425128 90)
			(size 0.519938 1.4986)
			(layers "F.Cu" "F.Mask" "F.Paste")
			(net "GND")
		)
		(pad "111" smd rect
			(at -2.050034 35.275012 90)
			(size 0.519938 1.4986)
			(layers "F.Cu" "F.Mask" "F.Paste")
			(net "M_K_CPU0_SB_DQ<8>")
		)
		(pad "112" smd rect
			(at -2.050034 36.124896 90)
			(size 0.519938 1.4986)
			(layers "F.Cu" "F.Mask" "F.Paste")
			(net "GND")
		)
		(pad "113" smd rect
			(at -2.050034 36.975034 90)
			(size 0.519938 1.4986)
			(layers "F.Cu" "F.Mask" "F.Paste")
			(net "M_K_CPU0_SB_DQ<9>")
		)
		(pad "114" smd rect
			(at -2.050034 37.824918 90)
			(size 0.519938 1.4986)
			(layers "F.Cu" "F.Mask" "F.Paste")
			(net "GND")
		)
		(pad "115" smd rect
			(at -2.050034 38.675056 90)
			(size 0.519938 1.4986)
			(layers "F.Cu" "F.Mask" "F.Paste")
			(net "M_K_CPU0_SB_DQS_DP<1>")
		)
		(pad "116" smd rect
			(at -2.050034 39.52494 90)
			(size 0.519938 1.4986)
			(layers "F.Cu" "F.Mask" "F.Paste")
			(net "M_K_CPU0_SB_DQS_DN<1>")
		)
		(pad "117" smd rect
			(at -2.050034 40.375078 90)
			(size 0.519938 1.4986)
			(layers "F.Cu" "F.Mask" "F.Paste")
			(net "GND")
		)
		(pad "118" smd rect
			(at -2.050034 41.224962 90)
			(size 0.519938 1.4986)
			(layers "F.Cu" "F.Mask" "F.Paste")
			(net "M_K_CPU0_SB_DQ<12>")
		)
		(pad "119" smd rect
			(at -2.050034 42.0751 90)
			(size 0.519938 1.4986)
			(layers "F.Cu" "F.Mask" "F.Paste")
			(net "GND")
		)
		(pad "120" smd rect
			(at -2.050034 42.924984 90)
			(size 0.519938 1.4986)
			(layers "F.Cu" "F.Mask" "F.Paste")
			(net "M_K_CPU0_SB_DQ<13>")
		)
		(pad "121" smd rect
			(at -2.050034 43.775122 90)
			(size 0.519938 1.4986)
			(layers "F.Cu" "F.Mask" "F.Paste")
			(net "GND")
		)
		(pad "122" smd rect
			(at -2.050034 44.625006 90)
			(size 0.519938 1.4986)
			(layers "F.Cu" "F.Mask" "F.Paste")
			(net "M_K_CPU0_SB_DQ<16>")
		)
		(pad "123" smd rect
			(at -2.050034 45.47489 90)
			(size 0.519938 1.4986)
			(layers "F.Cu" "F.Mask" "F.Paste")
			(net "GND")
		)
		(pad "124" smd rect
			(at -2.050034 46.325028 90)
			(size 0.519938 1.4986)
			(layers "F.Cu" "F.Mask" "F.Paste")
			(net "M_K_CPU0_SB_DQ<17>")
		)
		(pad "125" smd rect
			(at -2.050034 47.174912 90)
			(size 0.519938 1.4986)
			(layers "F.Cu" "F.Mask" "F.Paste")
			(net "GND")
		)
		(pad "126" smd rect
			(at -2.050034 48.02505 90)
			(size 0.519938 1.4986)
			(layers "F.Cu" "F.Mask" "F.Paste")
			(net "M_K_CPU0_SB_DQS_DP<2>")
		)
		(pad "127" smd rect
			(at -2.050034 48.874934 90)
			(size 0.519938 1.4986)
			(layers "F.Cu" "F.Mask" "F.Paste")
			(net "M_K_CPU0_SB_DQS_DN<2>")
		)
		(pad "128" smd rect
			(at -2.050034 49.725072 90)
			(size 0.519938 1.4986)
			(layers "F.Cu" "F.Mask" "F.Paste")
			(net "GND")
		)
		(pad "129" smd rect
			(at -2.050034 50.574956 90)
			(size 0.519938 1.4986)
			(layers "F.Cu" "F.Mask" "F.Paste")
			(net "M_K_CPU0_SB_DQ<20>")
		)
		(pad "130" smd rect
			(at -2.050034 51.425094 90)
			(size 0.519938 1.4986)
			(layers "F.Cu" "F.Mask" "F.Paste")
			(net "GND")
		)
		(pad "131" smd rect
			(at -2.050034 52.274978 90)
			(size 0.519938 1.4986)
			(layers "F.Cu" "F.Mask" "F.Paste")
			(net "M_K_CPU0_SB_DQ<21>")
		)
		(pad "132" smd rect
			(at -2.050034 53.125116 90)
			(size 0.519938 1.4986)
			(layers "F.Cu" "F.Mask" "F.Paste")
			(net "GND")
		)
		(pad "133" smd rect
			(at -2.050034 53.975 90)
			(size 0.519938 1.4986)
			(layers "F.Cu" "F.Mask" "F.Paste")
			(net "M_K_CPU0_SB_DQ<24>")
		)
		(pad "134" smd rect
			(at -2.050034 54.824884 90)
			(size 0.519938 1.4986)
			(layers "F.Cu" "F.Mask" "F.Paste")
			(net "GND")
		)
		(pad "135" smd rect
			(at -2.050034 55.675022 90)
			(size 0.519938 1.4986)
			(layers "F.Cu" "F.Mask" "F.Paste")
			(net "M_K_CPU0_SB_DQ<25>")
		)
		(pad "136" smd rect
			(at -2.050034 56.524906 90)
			(size 0.519938 1.4986)
			(layers "F.Cu" "F.Mask" "F.Paste")
			(net "GND")
		)
		(pad "137" smd rect
			(at -2.050034 57.375044 90)
			(size 0.519938 1.4986)
			(layers "F.Cu" "F.Mask" "F.Paste")
			(net "M_K_CPU0_SB_DQS_DP<3>")
		)
		(pad "138" smd rect
			(at -2.050034 58.224928 90)
			(size 0.519938 1.4986)
			(layers "F.Cu" "F.Mask" "F.Paste")
			(net "M_K_CPU0_SB_DQS_DN<3>")
		)
	)
)
